# S9S_MB_2U (Grand Teton) — schematic netlist excerpt (pin names and nets, part order shuffled) for the footprints in the layout excerpt that follows; sources: Cadence DE-HDL packaged netlist, KiCad conversion of 03242023_DA0F0TMBIJ0_F0T_Motherboard_J_brd_V01_OCP.brd

PR1787  Q_RES  3.3 1% CHIP  pkg 0402LF  page 267 : A = SW_PVCCIN_CPU0_BOOT1 ; B = SW_PVCCIN_CPU0_BOOT1_R
PC253_P0_5  Q_CAP  3300PF 50V 10% X7R  pkg 0402  page 269 : A = SW_P12V_PVCCIN_CPU0_FLT ; B = GND

(kicad_pcb
	(version 20260206)
	(generator "pcbnew")
	(generator_version "10.0")
	(general
		(thickness 1.6)
		(legacy_teardrops no)
	)
	(paper "A4")
	(title_block
		(title "03242023_DA0F0TMBIJ0_F0T_Motherboard_J_brd_V01_OCP.brd")
		(comment 1 "Grand Teton / footprints 2528-2529 of 6105")
	)
	(layers
		(0 "F.Cu" signal "TOP")
		(4 "In1.Cu" signal "GND")
		(6 "In2.Cu" signal "IN1")
		(8 "In3.Cu" signal "GND1")
		(10 "In4.Cu" signal "IN2")
		(12 "In5.Cu" signal "GND2")
		(14 "In6.Cu" signal "IN3")
		(16 "In7.Cu" signal "GND3")
		(18 "In8.Cu" signal "VCC")
		(20 "In9.Cu" signal "VCC1")
		(22 "In10.Cu" signal "GND4")
		(24 "In11.Cu" signal "IN4")
		(26 "In12.Cu" signal "GND5")
		(28 "In13.Cu" signal "IN5")
		(30 "In14.Cu" signal "GND6")
		(32 "In15.Cu" signal "IN6")
		(34 "In16.Cu" signal "GND7")
		(2 "B.Cu" signal "BOTTOM")
		(9 "F.Adhes" user "F.Adhesive")
		(11 "B.Adhes" user "B.Adhesive")
		(13 "F.Paste" user "Package Geometry/Pastemask Top")
		(15 "B.Paste" user "Package Geometry/Pastemask Bottom")
		(5 "F.SilkS" user "Ref Des/Silkscreen Top")
		(7 "B.SilkS" user "Ref Des/Silkscreen Bottom")
		(1 "F.Mask" user "Board Geometry/Soldermask Top")
		(3 "B.Mask" user "Board Geometry/Soldermask Bottom")
		(17 "Dwgs.User" user "User.Drawings")
		(19 "Cmts.User" user "User.Comments")
		(21 "Eco1.User" user "User.Eco1")
		(23 "Eco2.User" user "User.Eco2")
		(25 "Edge.Cuts" user "Board Geometry/Outline")
		(27 "Margin" user)
		(31 "F.CrtYd" user "Package Geometry/Place Bound Top")
		(29 "B.CrtYd" user "Package Geometry/Place Bound Bottom")
		(35 "F.Fab" user "Ref Des/Assembly Top")
		(33 "B.Fab" user "Ref Des/Assembly Bottom")
	)
	(footprint ""
		(layer "F.Cu")
		(at 345.98483 -338.180172 90)
		(property "Reference" "PR1787"
			(at 0 0 90)
			(layer "F.SilkS")
			(hide yes)
			(effects
				(font
					(size 1.27 1.27)
				)
			)
		)
		(property "Value" ""
			(at 0 0 90)
			(layer "F.Fab")
			(effects
				(font
					(size 1.27 1.27)
				)
			)
		)
		(duplicate_pad_numbers_are_jumpers no)
		(fp_line
			(start 0.7874 -0.4064)
			(end 0.7874 0.4064)
			(stroke
				(width 0.1524)
				(type default)
			)
			(layer "F.SilkS")
		)
		(fp_line
			(start -0.7874 -0.4064)
			(end 0.7874 -0.4064)
			(stroke
				(width 0.1524)
				(type default)
			)
			(layer "F.SilkS")
		)
		(fp_line
			(start 0.7874 0.4064)
			(end -0.7874 0.4064)
			(stroke
				(width 0.1524)
				(type default)
			)
			(layer "F.SilkS")
		)
		(fp_line
			(start -0.7874 0.4064)
			(end -0.7874 -0.4064)
			(stroke
				(width 0.1524)
				(type default)
			)
			(layer "F.SilkS")
		)
		(fp_line
			(start -0.12065 -0.305054)
			(end -0.12065 -0.2794)
			(stroke
				(width 0.1)
				(type default)
			)
			(layer "F.Fab")
		)
		(fp_line
			(start -0.67945 -0.305054)
			(end -0.12065 -0.305054)
			(stroke
				(width 0.1)
				(type default)
			)
			(layer "F.Fab")
		)
		(fp_line
			(start 0.67945 -0.3048)
			(end 0.67945 0.3048)
			(stroke
				(width 0.1)
				(type default)
			)
			(layer "F.Fab")
		)
		(fp_line
			(start 0.12065 -0.3048)
			(end 0.67945 -0.3048)
			(stroke
				(width 0.1)
				(type default)
			)
			(layer "F.Fab")
		)
		(fp_line
			(start 0.12065 -0.2794)
			(end 0.12065 -0.3048)
			(stroke
				(width 0.1)
				(type default)
			)
			(layer "F.Fab")
		)
		(fp_line
			(start -0.12065 -0.2794)
			(end 0.12065 -0.2794)
			(stroke
				(width 0.1)
				(type default)
			)
			(layer "F.Fab")
		)
		(fp_line
			(start 0.120396 0.2794)
			(end -0.12065 0.2794)
			(stroke
				(width 0.1)
				(type default)
			)
			(layer "F.Fab")
		)
		(fp_line
			(start -0.12065 0.2794)
			(end -0.12065 0.3048)
			(stroke
				(width 0.1)
				(type default)
			)
			(layer "F.Fab")
		)
		(fp_line
			(start 0.67945 0.3048)
			(end 0.120396 0.3048)
			(stroke
				(width 0.1)
				(type default)
			)
			(layer "F.Fab")
		)
		(fp_line
			(start 0.120396 0.3048)
			(end 0.120396 0.2794)
			(stroke
				(width 0.1)
				(type default)
			)
			(layer "F.Fab")
		)
		(fp_line
			(start -0.12065 0.3048)
			(end -0.67945 0.3048)
			(stroke
				(width 0.1)
				(type default)
			)
			(layer "F.Fab")
		)
		(fp_line
			(start -0.67945 0.3048)
			(end -0.67945 -0.305054)
			(stroke
				(width 0.1)
				(type default)
			)
			(layer "F.Fab")
		)
		(pad "1" smd circle
			(at -0.40005 0 90)
			(size 0 0)
			(layers "F.Cu" "F.Mask" "F.Paste")
			(net "SW_PVCCIN_CPU0_BOOT1")
		)
		(pad "2" smd circle
			(at 0.40005 0 90)
			(size 0 0)
			(layers "F.Cu" "F.Mask" "F.Paste")
			(net "SW_PVCCIN_CPU0_BOOT1_R")
		)
	)
	(footprint ""
		(layer "F.Cu")
		(at 381.756666 -340.064598)
		(property "Reference" "PC253_P0_5"
			(at 0 0 0)
			(layer "F.SilkS")
			(hide yes)
			(effects
				(font
					(size 1.27 1.27)
				)
			)
		)
		(property "Value" ""
			(at 0 0 0)
			(layer "F.Fab")
			(effects
				(font
					(size 1.27 1.27)
				)
			)
		)
		(duplicate_pad_numbers_are_jumpers no)
		(fp_line
			(start -0.7874 -0.4064)
			(end 0.7874 -0.4064)
			(stroke
				(width 0.1524)
				(type default)
			)
			(layer "F.SilkS")
		)
		(fp_line
			(start -0.7874 0.4064)
			(end -0.7874 -0.4064)
			(stroke
				(width 0.1524)
				(type default)
			)
			(layer "F.SilkS")
		)
		(fp_line
			(start 0.7874 -0.4064)
			(end 0.7874 0.4064)
			(stroke
				(width 0.1524)
				(type default)
			)
			(layer "F.SilkS")
		)
		(fp_line
			(start 0.7874 0.4064)
			(end -0.7874 0.4064)
			(stroke
				(width 0.1524)
				(type default)
			)
			(layer "F.SilkS")
		)
		(fp_line
			(start -0.67945 -0.305054)
			(end -0.12065 -0.305054)
			(stroke
				(width 0.1)
				(type default)
			)
			(layer "F.Fab")
		)
		(fp_line
			(start -0.67945 0.3048)
			(end -0.67945 -0.305054)
			(stroke
				(width 0.1)
				(type default)
			)
			(layer "F.Fab")
		)
		(fp_line
			(start -0.12065 -0.305054)
			(end -0.12065 -0.2794)
			(stroke
				(width 0.1)
				(type default)
			)
			(layer "F.Fab")
		)
		(fp_line
			(start -0.12065 -0.2794)
			(end 0.12065 -0.2794)
			(stroke
				(width 0.1)
				(type default)
			)
			(layer "F.Fab")
		)
		(fp_line
			(start -0.12065 0.2794)
			(end -0.12065 0.3048)
			(stroke
				(width 0.1)
				(type default)
			)
			(layer "F.Fab")
		)
		(fp_line
			(start -0.12065 0.3048)
			(end -0.67945 0.3048)
			(stroke
				(width 0.1)
				(type default)
			)
			(layer "F.Fab")
		)
		(fp_line
			(start 0.120396 0.2794)
			(end -0.12065 0.2794)
			(stroke
				(width 0.1)
				(type default)
			)
			(layer "F.Fab")
		)
		(fp_line
			(start 0.120396 0.3048)
			(end 0.120396 0.2794)
			(stroke
				(width 0.1)
				(type default)
			)
			(layer "F.Fab")
		)
		(fp_line
			(start 0.12065 -0.3048)
			(end 0.67945 -0.3048)
			(stroke
				(width 0.1)
				(type default)
			)
			(layer "F.Fab")
		)
		(fp_line
			(start 0.12065 -0.2794)
			(end 0.12065 -0.3048)
			(stroke
				(width 0.1)
				(type default)
			)
			(layer "F.Fab")
		)
		(fp_line
			(start 0.67945 -0.3048)
			(end 0.67945 0.3048)
			(stroke
				(width 0.1)
				(type default)
			)
			(layer "F.Fab")
		)
		(fp_line
			(start 0.67945 0.3048)
			(end 0.120396 0.3048)
			(stroke
				(width 0.1)
				(type default)
			)
			(layer "F.Fab")
		)
		(pad "1" smd circle
			(at -0.40005 0)
			(size 0 0)
			(layers "F.Cu" "F.Mask" "F.Paste")
			(net "SW_P12V_PVCCIN_CPU0_FLT")
		)
		(pad "2" smd circle
			(at 0.40005 0)
			(size 0 0)
			(layers "F.Cu" "F.Mask" "F.Paste")
			(net "GND")
		)
	)
)
